(kicad_pcb
	(version 20260206)
	(generator "pcbnew")
	(generator_version "10.0")
	(general
		(thickness 1.6)
		(legacy_teardrops no)
	)
	(paper "A4")
	(title_block
		(title "04192023_DAF0TMB3IC0_F0TG_MB_C_brd_V02_OCP.brd")
		(comment 1 "Grand Teton / footprint 3 of 8354 (J21), pads 227-291 of 291")
	)
	(layers
		(0 "F.Cu" signal "TOP")
		(4 "In1.Cu" signal "GND")
		(6 "In2.Cu" signal "IN1")
		(8 "In3.Cu" signal "GND1")
		(10 "In4.Cu" signal "IN2")
		(12 "In5.Cu" signal "GND2")
		(14 "In6.Cu" signal "IN3")
		(16 "In7.Cu" signal "GND3")
		(18 "In8.Cu" signal "VCC")
		(20 "In9.Cu" signal "VCC1")
		(22 "In10.Cu" signal "GND4")
		(24 "In11.Cu" signal "IN4")
		(26 "In12.Cu" signal "GND5")
		(28 "In13.Cu" signal "IN5")
		(30 "In14.Cu" signal "GND6")
		(32 "In15.Cu" signal "IN6")
		(34 "In16.Cu" signal "GND7")
		(2 "B.Cu" signal "BOTTOM")
		(9 "F.Adhes" user "F.Adhesive")
		(11 "B.Adhes" user "B.Adhesive")
		(13 "F.Paste" user "Package Geometry/Pastemask Top")
		(15 "B.Paste" user "Package Geometry/Pastemask Bottom")
		(5 "F.SilkS" user "Ref Des/Silkscreen Top")
		(7 "B.SilkS" user "Ref Des/Silkscreen Bottom")
		(1 "F.Mask" user "Board Geometry/Soldermask Top")
		(3 "B.Mask" user "Board Geometry/Soldermask Bottom")
		(17 "Dwgs.User" user "User.Drawings")
		(19 "Cmts.User" user "User.Comments")
		(21 "Eco1.User" user "User.Eco1")
		(23 "Eco2.User" user "User.Eco2")
		(25 "Edge.Cuts" user "Board Geometry/Outline")
		(27 "Margin" user)
		(31 "F.CrtYd" user "Package Geometry/Place Bound Top")
		(29 "B.CrtYd" user "Package Geometry/Place Bound Bottom")
		(35 "F.Fab" user "Ref Des/Assembly Top")
		(33 "B.Fab" user "Ref Des/Assembly Bottom")
	)
	(footprint ""
		(layer "F.Cu")
		(at 275.142198 -255.560068 180)
		(property "Reference" "J21"
			(at -2.2098 -81.984088 0)
			(unlocked yes)
			(layer "F.SilkS")
			(effects
				(font
					(size 0.7874 0.5842)
					(thickness 0.1524)
				)
			)
		)
		(property "Value" ""
			(at 0 0 180)
			(layer "F.Fab")
			(effects
				(font
					(size 1.27 1.27)
				)
			)
		)
		(duplicate_pad_numbers_are_jumpers no)
		(pad "227" smd rect
			(at 2.050034 11.474958 90)
			(size 0.519938 1.4986)
			(layers "F.Cu" "F.Mask" "F.Paste")
			(net "M_E_CPU0_SB_PAR")
		)
		(pad "228" smd rect
			(at 2.050034 12.325096 90)
			(size 0.519938 1.4986)
			(layers "F.Cu" "F.Mask" "F.Paste")
			(net "GND")
		)
		(pad "229" smd rect
			(at 2.050034 13.17498 90)
			(size 0.519938 1.4986)
			(layers "F.Cu" "F.Mask" "F.Paste")
			(net "M_E_CPU0_SB_CS_N<1>")
		)
		(pad "230" smd rect
			(at 2.050034 14.025118 90)
			(size 0.519938 1.4986)
			(layers "F.Cu" "F.Mask" "F.Paste")
			(net "GND")
		)
		(pad "231" smd rect
			(at 2.050034 14.875002 90)
			(size 0.519938 1.4986)
			(layers "F.Cu" "F.Mask" "F.Paste")
			(net "Net_2310")
		)
		(pad "232" smd rect
			(at 2.050034 15.724886 90)
			(size 0.519938 1.4986)
			(layers "F.Cu" "F.Mask" "F.Paste")
			(net "Net_2311")
		)
		(pad "233" smd rect
			(at 2.050034 16.575024 90)
			(size 0.519938 1.4986)
			(layers "F.Cu" "F.Mask" "F.Paste")
			(net "GND")
		)
		(pad "234" smd rect
			(at 2.050034 17.424908 90)
			(size 0.519938 1.4986)
			(layers "F.Cu" "F.Mask" "F.Paste")
			(net "M_E_CPU0_SB_CB<6>")
		)
		(pad "235" smd rect
			(at 2.050034 18.275046 90)
			(size 0.519938 1.4986)
			(layers "F.Cu" "F.Mask" "F.Paste")
			(net "GND")
		)
		(pad "236" smd rect
			(at 2.050034 19.12493 90)
			(size 0.519938 1.4986)
			(layers "F.Cu" "F.Mask" "F.Paste")
			(net "M_E_CPU0_SB_CB<7>")
		)
		(pad "237" smd rect
			(at 2.050034 19.975068 90)
			(size 0.519938 1.4986)
			(layers "F.Cu" "F.Mask" "F.Paste")
			(net "GND")
		)
		(pad "238" smd rect
			(at 2.050034 20.824952 90)
			(size 0.519938 1.4986)
			(layers "F.Cu" "F.Mask" "F.Paste")
			(net "M_E_CPU0_SB_DQS_DN<4>")
		)
		(pad "239" smd rect
			(at 2.050034 21.67509 90)
			(size 0.519938 1.4986)
			(layers "F.Cu" "F.Mask" "F.Paste")
			(net "M_E_CPU0_SB_DQS_DP<4>")
		)
		(pad "240" smd rect
			(at 2.050034 22.524974 90)
			(size 0.519938 1.4986)
			(layers "F.Cu" "F.Mask" "F.Paste")
			(net "GND")
		)
		(pad "241" smd rect
			(at 2.050034 23.375112 90)
			(size 0.519938 1.4986)
			(layers "F.Cu" "F.Mask" "F.Paste")
			(net "M_E_CPU0_SB_CB<2>")
		)
		(pad "242" smd rect
			(at 2.050034 24.224996 90)
			(size 0.519938 1.4986)
			(layers "F.Cu" "F.Mask" "F.Paste")
			(net "GND")
		)
		(pad "243" smd rect
			(at 2.050034 25.07488 90)
			(size 0.519938 1.4986)
			(layers "F.Cu" "F.Mask" "F.Paste")
			(net "M_E_CPU0_SB_CB<3>")
		)
		(pad "244" smd rect
			(at 2.050034 25.925018 90)
			(size 0.519938 1.4986)
			(layers "F.Cu" "F.Mask" "F.Paste")
			(net "GND")
		)
		(pad "245" smd rect
			(at 2.050034 26.774902 90)
			(size 0.519938 1.4986)
			(layers "F.Cu" "F.Mask" "F.Paste")
			(net "M_E_CPU0_SB_DQ<2>")
		)
		(pad "246" smd rect
			(at 2.050034 27.62504 90)
			(size 0.519938 1.4986)
			(layers "F.Cu" "F.Mask" "F.Paste")
			(net "GND")
		)
		(pad "247" smd rect
			(at 2.050034 28.474924 90)
			(size 0.519938 1.4986)
			(layers "F.Cu" "F.Mask" "F.Paste")
			(net "M_E_CPU0_SB_DQ<3>")
		)
		(pad "248" smd rect
			(at 2.050034 29.325062 90)
			(size 0.519938 1.4986)
			(layers "F.Cu" "F.Mask" "F.Paste")
			(net "GND")
		)
		(pad "249" smd rect
			(at 2.050034 30.174946 90)
			(size 0.519938 1.4986)
			(layers "F.Cu" "F.Mask" "F.Paste")
			(net "M_E_CPU0_SB_DQS_DN<5>")
		)
		(pad "250" smd rect
			(at 2.050034 31.025084 90)
			(size 0.519938 1.4986)
			(layers "F.Cu" "F.Mask" "F.Paste")
			(net "M_E_CPU0_SB_DQS_DP<5>")
		)
		(pad "251" smd rect
			(at 2.050034 31.874968 90)
			(size 0.519938 1.4986)
			(layers "F.Cu" "F.Mask" "F.Paste")
			(net "GND")
		)
		(pad "252" smd rect
			(at 2.050034 32.725106 90)
			(size 0.519938 1.4986)
			(layers "F.Cu" "F.Mask" "F.Paste")
			(net "M_E_CPU0_SB_DQ<6>")
		)
		(pad "253" smd rect
			(at 2.050034 33.57499 90)
			(size 0.519938 1.4986)
			(layers "F.Cu" "F.Mask" "F.Paste")
			(net "GND")
		)
		(pad "254" smd rect
			(at 2.050034 34.425128 90)
			(size 0.519938 1.4986)
			(layers "F.Cu" "F.Mask" "F.Paste")
			(net "M_E_CPU0_SB_DQ<7>")
		)
		(pad "255" smd rect
			(at 2.050034 35.275012 90)
			(size 0.519938 1.4986)
			(layers "F.Cu" "F.Mask" "F.Paste")
			(net "GND")
		)
		(pad "256" smd rect
			(at 2.050034 36.124896 90)
			(size 0.519938 1.4986)
			(layers "F.Cu" "F.Mask" "F.Paste")
			(net "M_E_CPU0_SB_DQ<10>")
		)
		(pad "257" smd rect
			(at 2.050034 36.975034 90)
			(size 0.519938 1.4986)
			(layers "F.Cu" "F.Mask" "F.Paste")
			(net "GND")
		)
		(pad "258" smd rect
			(at 2.050034 37.824918 90)
			(size 0.519938 1.4986)
			(layers "F.Cu" "F.Mask" "F.Paste")
			(net "M_E_CPU0_SB_DQ<11>")
		)
		(pad "259" smd rect
			(at 2.050034 38.675056 90)
			(size 0.519938 1.4986)
			(layers "F.Cu" "F.Mask" "F.Paste")
			(net "GND")
		)
		(pad "260" smd rect
			(at 2.050034 39.52494 90)
			(size 0.519938 1.4986)
			(layers "F.Cu" "F.Mask" "F.Paste")
			(net "M_E_CPU0_SB_DQS_DN<6>")
		)
		(pad "261" smd rect
			(at 2.050034 40.375078 90)
			(size 0.519938 1.4986)
			(layers "F.Cu" "F.Mask" "F.Paste")
			(net "M_E_CPU0_SB_DQS_DP<6>")
		)
		(pad "262" smd rect
			(at 2.050034 41.224962 90)
			(size 0.519938 1.4986)
			(layers "F.Cu" "F.Mask" "F.Paste")
			(net "GND")
		)
		(pad "263" smd rect
			(at 2.050034 42.0751 90)
			(size 0.519938 1.4986)
			(layers "F.Cu" "F.Mask" "F.Paste")
			(net "M_E_CPU0_SB_DQ<14>")
		)
		(pad "264" smd rect
			(at 2.050034 42.924984 90)
			(size 0.519938 1.4986)
			(layers "F.Cu" "F.Mask" "F.Paste")
			(net "GND")
		)
		(pad "265" smd rect
			(at 2.050034 43.775122 90)
			(size 0.519938 1.4986)
			(layers "F.Cu" "F.Mask" "F.Paste")
			(net "M_E_CPU0_SB_DQ<15>")
		)
		(pad "266" smd rect
			(at 2.050034 44.625006 90)
			(size 0.519938 1.4986)
			(layers "F.Cu" "F.Mask" "F.Paste")
			(net "GND")
		)
		(pad "267" smd rect
			(at 2.050034 45.47489 90)
			(size 0.519938 1.4986)
			(layers "F.Cu" "F.Mask" "F.Paste")
			(net "M_E_CPU0_SB_DQ<18>")
		)
		(pad "268" smd rect
			(at 2.050034 46.325028 90)
			(size 0.519938 1.4986)
			(layers "F.Cu" "F.Mask" "F.Paste")
			(net "GND")
		)
		(pad "269" smd rect
			(at 2.050034 47.174912 90)
			(size 0.519938 1.4986)
			(layers "F.Cu" "F.Mask" "F.Paste")
			(net "M_E_CPU0_SB_DQ<19>")
		)
		(pad "270" smd rect
			(at 2.050034 48.02505 90)
			(size 0.519938 1.4986)
			(layers "F.Cu" "F.Mask" "F.Paste")
			(net "GND")
		)
		(pad "271" smd rect
			(at 2.050034 48.874934 90)
			(size 0.519938 1.4986)
			(layers "F.Cu" "F.Mask" "F.Paste")
			(net "M_E_CPU0_SB_DQS_DN<7>")
		)
		(pad "272" smd rect
			(at 2.050034 49.725072 90)
			(size 0.519938 1.4986)
			(layers "F.Cu" "F.Mask" "F.Paste")
			(net "M_E_CPU0_SB_DQS_DP<7>")
		)
		(pad "273" smd rect
			(at 2.050034 50.574956 90)
			(size 0.519938 1.4986)
			(layers "F.Cu" "F.Mask" "F.Paste")
			(net "GND")
		)
		(pad "274" smd rect
			(at 2.050034 51.425094 90)
			(size 0.519938 1.4986)
			(layers "F.Cu" "F.Mask" "F.Paste")
			(net "M_E_CPU0_SB_DQ<22>")
		)
		(pad "275" smd rect
			(at 2.050034 52.274978 90)
			(size 0.519938 1.4986)
			(layers "F.Cu" "F.Mask" "F.Paste")
			(net "GND")
		)
		(pad "276" smd rect
			(at 2.050034 53.125116 90)
			(size 0.519938 1.4986)
			(layers "F.Cu" "F.Mask" "F.Paste")
			(net "M_E_CPU0_SB_DQ<23>")
		)
		(pad "277" smd rect
			(at 2.050034 53.975 90)
			(size 0.519938 1.4986)
			(layers "F.Cu" "F.Mask" "F.Paste")
			(net "GND")
		)
		(pad "278" smd rect
			(at 2.050034 54.824884 90)
			(size 0.519938 1.4986)
			(layers "F.Cu" "F.Mask" "F.Paste")
			(net "M_E_CPU0_SB_DQ<26>")
		)
		(pad "279" smd rect
			(at 2.050034 55.675022 90)
			(size 0.519938 1.4986)
			(layers "F.Cu" "F.Mask" "F.Paste")
			(net "GND")
		)
		(pad "280" smd rect
			(at 2.050034 56.524906 90)
			(size 0.519938 1.4986)
			(layers "F.Cu" "F.Mask" "F.Paste")
			(net "M_E_CPU0_SB_DQ<27>")
		)
		(pad "281" smd rect
			(at 2.050034 57.375044 90)
			(size 0.519938 1.4986)
			(layers "F.Cu" "F.Mask" "F.Paste")
			(net "GND")
		)
		(pad "282" smd rect
			(at 2.050034 58.224928 90)
			(size 0.519938 1.4986)
			(layers "F.Cu" "F.Mask" "F.Paste")
			(net "M_E_CPU0_SB_DQS_DN<8>")
		)
		(pad "283" smd rect
			(at 2.050034 59.075066 90)
			(size 0.519938 1.4986)
			(layers "F.Cu" "F.Mask" "F.Paste")
			(net "M_E_CPU0_SB_DQS_DP<8>")
		)
		(pad "284" smd rect
			(at 2.050034 59.92495 90)
			(size 0.519938 1.4986)
			(layers "F.Cu" "F.Mask" "F.Paste")
			(net "GND")
		)
		(pad "285" smd rect
			(at 2.050034 60.775088 90)
			(size 0.519938 1.4986)
			(layers "F.Cu" "F.Mask" "F.Paste")
			(net "M_E_CPU0_SB_DQ<30>")
		)
		(pad "286" smd rect
			(at 2.050034 61.624972 90)
			(size 0.519938 1.4986)
			(layers "F.Cu" "F.Mask" "F.Paste")
			(net "GND")
		)
		(pad "287" smd rect
			(at 2.050034 62.47511 90)
			(size 0.519938 1.4986)
			(layers "F.Cu" "F.Mask" "F.Paste")
			(net "M_E_CPU0_SB_DQ<31>")
		)
		(pad "288" smd rect
			(at 2.050034 63.324994 90)
			(size 0.519938 1.4986)
			(layers "F.Cu" "F.Mask" "F.Paste")
			(net "GND")
		)
		(pad "G1" thru_hole oval
			(at 0 -68.97497 90)
			(size 1.7272 3.4798)
			(drill oval 1.2192 2.4638)
			(layers "*.Cu" "*.Mask")
			(remove_unused_layers no)
			(net "GND")
			(clearance 0.127)
			(thermal_gap 0.127)
		)
		(pad "G2" thru_hole oval
			(at 0 3.875024 90)
			(size 1.7272 3.4798)
			(drill oval 1.2192 2.4638)
			(layers "*.Cu" "*.Mask")
			(remove_unused_layers no)
			(net "GND")
			(clearance 0.127)
			(thermal_gap 0.127)
		)
		(pad "G3" thru_hole oval
			(at 0 68.97497 90)
			(size 1.7272 3.4798)
			(drill oval 1.2192 2.4638)
			(layers "*.Cu" "*.Mask")
			(remove_unused_layers no)
			(net "GND")
			(clearance 0.127)
			(thermal_gap 0.127)
		)
	)
)
